# S9S_MB_2U (Grand Teton) — schematic netlist excerpt (pin names and nets, part order shuffled) for the footprints in the layout excerpt that follows; sources: Cadence DE-HDL packaged netlist, KiCad conversion of 03242023_DA0F0TMBIJ0_F0T_Motherboard_J_brd_V01_OCP.brd

C1277  Q_CAP  22UF 16V 20% X6S  pkg C0805  page 191 : A = P12V_E1S_0 ; B = GND
R4188  Q_RES  1K 1% EMPTY  pkg 0402LF  page 170 : A = P3V3_AUX ; B = U271_1_ADD2
R3249  Q_RES  10K 1% CHIP  pkg 0402LF  page 216 : A = P3V3_AUX ; B = PU_FPGA_D12_PROGRAMN

(kicad_pcb
	(version 20260206)
	(generator "pcbnew")
	(generator_version "10.0")
	(general
		(thickness 1.6)
		(legacy_teardrops no)
	)
	(paper "A4")
	(title_block
		(title "03242023_DA0F0TMBIJ0_F0T_Motherboard_J_brd_V01_OCP.brd")
		(comment 1 "Grand Teton / footprints 1919-1921 of 6105")
	)
	(layers
		(0 "F.Cu" signal "TOP")
		(4 "In1.Cu" signal "GND")
		(6 "In2.Cu" signal "IN1")
		(8 "In3.Cu" signal "GND1")
		(10 "In4.Cu" signal "IN2")
		(12 "In5.Cu" signal "GND2")
		(14 "In6.Cu" signal "IN3")
		(16 "In7.Cu" signal "GND3")
		(18 "In8.Cu" signal "VCC")
		(20 "In9.Cu" signal "VCC1")
		(22 "In10.Cu" signal "GND4")
		(24 "In11.Cu" signal "IN4")
		(26 "In12.Cu" signal "GND5")
		(28 "In13.Cu" signal "IN5")
		(30 "In14.Cu" signal "GND6")
		(32 "In15.Cu" signal "IN6")
		(34 "In16.Cu" signal "GND7")
		(2 "B.Cu" signal "BOTTOM")
		(9 "F.Adhes" user "F.Adhesive")
		(11 "B.Adhes" user "B.Adhesive")
		(13 "F.Paste" user "Package Geometry/Pastemask Top")
		(15 "B.Paste" user "Package Geometry/Pastemask Bottom")
		(5 "F.SilkS" user "Ref Des/Silkscreen Top")
		(7 "B.SilkS" user "Ref Des/Silkscreen Bottom")
		(1 "F.Mask" user "Board Geometry/Soldermask Top")
		(3 "B.Mask" user "Board Geometry/Soldermask Bottom")
		(17 "Dwgs.User" user "User.Drawings")
		(19 "Cmts.User" user "User.Comments")
		(21 "Eco1.User" user "User.Eco1")
		(23 "Eco2.User" user "User.Eco2")
		(25 "Edge.Cuts" user "Board Geometry/Outline")
		(27 "Margin" user)
		(31 "F.CrtYd" user "Package Geometry/Place Bound Top")
		(29 "B.CrtYd" user "Package Geometry/Place Bound Bottom")
		(35 "F.Fab" user "Ref Des/Assembly Top")
		(33 "B.Fab" user "Ref Des/Assembly Bottom")
	)
	(footprint ""
		(layer "F.Cu")
		(at 160.83788 -117.566948)
		(property "Reference" "R3249"
			(at 0 0 0)
			(layer "F.SilkS")
			(hide yes)
			(effects
				(font
					(size 1.27 1.27)
				)
			)
		)
		(property "Value" ""
			(at 0 0 0)
			(layer "F.Fab")
			(effects
				(font
					(size 1.27 1.27)
				)
			)
		)
		(duplicate_pad_numbers_are_jumpers no)
		(fp_line
			(start -0.7874 -0.4064)
			(end 0.7874 -0.4064)
			(stroke
				(width 0.1524)
				(type default)
			)
			(layer "F.SilkS")
		)
		(fp_line
			(start -0.7874 0.4064)
			(end -0.7874 -0.4064)
			(stroke
				(width 0.1524)
				(type default)
			)
			(layer "F.SilkS")
		)
		(fp_line
			(start 0.7874 -0.4064)
			(end 0.7874 0.4064)
			(stroke
				(width 0.1524)
				(type default)
			)
			(layer "F.SilkS")
		)
		(fp_line
			(start 0.7874 0.4064)
			(end -0.7874 0.4064)
			(stroke
				(width 0.1524)
				(type default)
			)
			(layer "F.SilkS")
		)
		(fp_line
			(start -0.67945 -0.305054)
			(end -0.12065 -0.305054)
			(stroke
				(width 0.1)
				(type default)
			)
			(layer "F.Fab")
		)
		(fp_line
			(start -0.67945 0.3048)
			(end -0.67945 -0.305054)
			(stroke
				(width 0.1)
				(type default)
			)
			(layer "F.Fab")
		)
		(fp_line
			(start -0.12065 -0.305054)
			(end -0.12065 -0.2794)
			(stroke
				(width 0.1)
				(type default)
			)
			(layer "F.Fab")
		)
		(fp_line
			(start -0.12065 -0.2794)
			(end 0.12065 -0.2794)
			(stroke
				(width 0.1)
				(type default)
			)
			(layer "F.Fab")
		)
		(fp_line
			(start -0.12065 0.2794)
			(end -0.12065 0.3048)
			(stroke
				(width 0.1)
				(type default)
			)
			(layer "F.Fab")
		)
		(fp_line
			(start -0.12065 0.3048)
			(end -0.67945 0.3048)
			(stroke
				(width 0.1)
				(type default)
			)
			(layer "F.Fab")
		)
		(fp_line
			(start 0.120396 0.2794)
			(end -0.12065 0.2794)
			(stroke
				(width 0.1)
				(type default)
			)
			(layer "F.Fab")
		)
		(fp_line
			(start 0.120396 0.3048)
			(end 0.120396 0.2794)
			(stroke
				(width 0.1)
				(type default)
			)
			(layer "F.Fab")
		)
		(fp_line
			(start 0.12065 -0.3048)
			(end 0.67945 -0.3048)
			(stroke
				(width 0.1)
				(type default)
			)
			(layer "F.Fab")
		)
		(fp_line
			(start 0.12065 -0.2794)
			(end 0.12065 -0.3048)
			(stroke
				(width 0.1)
				(type default)
			)
			(layer "F.Fab")
		)
		(fp_line
			(start 0.67945 -0.3048)
			(end 0.67945 0.3048)
			(stroke
				(width 0.1)
				(type default)
			)
			(layer "F.Fab")
		)
		(fp_line
			(start 0.67945 0.3048)
			(end 0.120396 0.3048)
			(stroke
				(width 0.1)
				(type default)
			)
			(layer "F.Fab")
		)
		(pad "1" smd circle
			(at -0.40005 0)
			(size 0 0)
			(layers "F.Cu" "F.Mask" "F.Paste")
			(net "P3V3_AUX")
		)
		(pad "2" smd circle
			(at 0.40005 0)
			(size 0 0)
			(layers "F.Cu" "F.Mask" "F.Paste")
			(net "PU_FPGA_D12_PROGRAMN")
		)
	)
	(footprint ""
		(layer "F.Cu")
		(at 297.152314 -14.506194 180)
		(property "Reference" "R4188"
			(at 0 0 180)
			(layer "F.SilkS")
			(hide yes)
			(effects
				(font
					(size 1.27 1.27)
				)
			)
		)
		(property "Value" ""
			(at 0 0 180)
			(layer "F.Fab")
			(effects
				(font
					(size 1.27 1.27)
				)
			)
		)
		(duplicate_pad_numbers_are_jumpers no)
		(fp_line
			(start 0.7874 0.4064)
			(end -0.7874 0.4064)
			(stroke
				(width 0.1524)
				(type default)
			)
			(layer "F.SilkS")
		)
		(fp_line
			(start 0.7874 -0.4064)
			(end 0.7874 0.4064)
			(stroke
				(width 0.1524)
				(type default)
			)
			(layer "F.SilkS")
		)
		(fp_line
			(start -0.7874 0.4064)
			(end -0.7874 -0.4064)
			(stroke
				(width 0.1524)
				(type default)
			)
			(layer "F.SilkS")
		)
		(fp_line
			(start -0.7874 -0.4064)
			(end 0.7874 -0.4064)
			(stroke
				(width 0.1524)
				(type default)
			)
			(layer "F.SilkS")
		)
		(fp_line
			(start 0.67945 0.3048)
			(end 0.120396 0.3048)
			(stroke
				(width 0.1)
				(type default)
			)
			(layer "F.Fab")
		)
		(fp_line
			(start 0.67945 -0.3048)
			(end 0.67945 0.3048)
			(stroke
				(width 0.1)
				(type default)
			)
			(layer "F.Fab")
		)
		(fp_line
			(start 0.12065 -0.2794)
			(end 0.12065 -0.3048)
			(stroke
				(width 0.1)
				(type default)
			)
			(layer "F.Fab")
		)
		(fp_line
			(start 0.12065 -0.3048)
			(end 0.67945 -0.3048)
			(stroke
				(width 0.1)
				(type default)
			)
			(layer "F.Fab")
		)
		(fp_line
			(start 0.120396 0.3048)
			(end 0.120396 0.2794)
			(stroke
				(width 0.1)
				(type default)
			)
			(layer "F.Fab")
		)
		(fp_line
			(start 0.120396 0.2794)
			(end -0.12065 0.2794)
			(stroke
				(width 0.1)
				(type default)
			)
			(layer "F.Fab")
		)
		(fp_line
			(start -0.12065 0.3048)
			(end -0.67945 0.3048)
			(stroke
				(width 0.1)
				(type default)
			)
			(layer "F.Fab")
		)
		(fp_line
			(start -0.12065 0.2794)
			(end -0.12065 0.3048)
			(stroke
				(width 0.1)
				(type default)
			)
			(layer "F.Fab")
		)
		(fp_line
			(start -0.12065 -0.2794)
			(end 0.12065 -0.2794)
			(stroke
				(width 0.1)
				(type default)
			)
			(layer "F.Fab")
		)
		(fp_line
			(start -0.12065 -0.305054)
			(end -0.12065 -0.2794)
			(stroke
				(width 0.1)
				(type default)
			)
			(layer "F.Fab")
		)
		(fp_line
			(start -0.67945 0.3048)
			(end -0.67945 -0.305054)
			(stroke
				(width 0.1)
				(type default)
			)
			(layer "F.Fab")
		)
		(fp_line
			(start -0.67945 -0.305054)
			(end -0.12065 -0.305054)
			(stroke
				(width 0.1)
				(type default)
			)
			(layer "F.Fab")
		)
		(pad "1" smd circle
			(at -0.40005 0 180)
			(size 0 0)
			(layers "F.Cu" "F.Mask" "F.Paste")
			(net "P3V3_AUX")
		)
		(pad "2" smd circle
			(at 0.40005 0 180)
			(size 0 0)
			(layers "F.Cu" "F.Mask" "F.Paste")
			(net "U271_1_ADD2")
		)
	)
	(footprint ""
		(layer "F.Cu")
		(at 248.845832 -39.21379 -90)
		(property "Reference" "C1277"
			(at 0 0 270)
			(layer "F.SilkS")
			(hide yes)
			(effects
				(font
					(size 1.27 1.27)
				)
			)
		)
		(property "Value" ""
			(at 0 0 270)
			(layer "F.Fab")
			(effects
				(font
					(size 1.27 1.27)
				)
			)
		)
		(duplicate_pad_numbers_are_jumpers no)
		(fp_line
			(start -1.524 0.762)
			(end -1.524 -0.762)
			(stroke
				(width 0.1524)
				(type default)
			)
			(layer "F.SilkS")
		)
		(fp_line
			(start 1.524 0.762)
			(end -1.524 0.762)
			(stroke
				(width 0.1524)
				(type default)
			)
			(layer "F.SilkS")
		)
		(fp_line
			(start -1.524 -0.762)
			(end 1.524 -0.762)
			(stroke
				(width 0.1524)
				(type default)
			)
			(layer "F.SilkS")
		)
		(fp_line
			(start 1.524 -0.762)
			(end 1.524 0.762)
			(stroke
				(width 0.1524)
				(type default)
			)
			(layer "F.SilkS")
		)
		(fp_line
			(start -1.1049 0.724916)
			(end 1.1049 0.724916)
			(stroke
				(width 0.1)
				(type default)
			)
			(layer "F.Fab")
		)
		(fp_line
			(start 1.1049 0.724916)
			(end 1.1049 -0.724916)
			(stroke
				(width 0.1)
				(type default)
			)
			(layer "F.Fab")
		)
		(fp_line
			(start -1.1049 -0.724916)
			(end -1.1049 0.724916)
			(stroke
				(width 0.1)
				(type default)
			)
			(layer "F.Fab")
		)
		(fp_line
			(start 1.1049 -0.724916)
			(end -1.1049 -0.724916)
			(stroke
				(width 0.1)
				(type default)
			)
			(layer "F.Fab")
		)
		(pad "1" smd rect
			(at -0.889 0 90)
			(size 1.016 1.27)
			(layers "F.Cu" "F.Mask" "F.Paste")
			(net "P12V_E1S_0")
		)
		(pad "2" smd rect
			(at 0.889 0 90)
			(size 1.016 1.27)
			(layers "F.Cu" "F.Mask" "F.Paste")
			(net "GND")
		)
	)
)
